# T6G (Grand Teton) — schematic netlist excerpt (pin names and nets, part order shuffled) for the footprints in the layout excerpt that follows; sources: Cadence DE-HDL packaged netlist, KiCad conversion of 04192023_DAF0TMB3IC0_F0TG_MB_C_brd_V02_OCP.brd

TP20  TP  NA  pkg TP  page 54 : TP = VSENSE_PVDDCR_SOC_P1_DP
R6229  Q_RES  0 5% CHIP  pkg 0402LF  page 252 : A = SMB_P12V_HSC_SCL_R ; B = SMB_P12V_HSC_SCL
R1015  Q_RES  1K 1% EMPTY  pkg 0201LF  page 287 : A = P1V8_CPU0_RT_1D ; B = RT_CPU0_P1_ADDR2
R2487  Q_RES  4.7K 1% EMPTY  pkg 0402LF  page 133 : A = P3V3_AUX ; B = IRQ_LVC3_WAKE_BUF_N

(kicad_pcb
	(version 20260206)
	(generator "pcbnew")
	(generator_version "10.0")
	(general
		(thickness 1.6)
		(legacy_teardrops no)
	)
	(paper "A4")
	(title_block
		(title "04192023_DAF0TMB3IC0_F0TG_MB_C_brd_V02_OCP.brd")
		(comment 1 "Grand Teton / footprints 1850-1853 of 8354")
	)
	(layers
		(0 "F.Cu" signal "TOP")
		(4 "In1.Cu" signal "GND")
		(6 "In2.Cu" signal "IN1")
		(8 "In3.Cu" signal "GND1")
		(10 "In4.Cu" signal "IN2")
		(12 "In5.Cu" signal "GND2")
		(14 "In6.Cu" signal "IN3")
		(16 "In7.Cu" signal "GND3")
		(18 "In8.Cu" signal "VCC")
		(20 "In9.Cu" signal "VCC1")
		(22 "In10.Cu" signal "GND4")
		(24 "In11.Cu" signal "IN4")
		(26 "In12.Cu" signal "GND5")
		(28 "In13.Cu" signal "IN5")
		(30 "In14.Cu" signal "GND6")
		(32 "In15.Cu" signal "IN6")
		(34 "In16.Cu" signal "GND7")
		(2 "B.Cu" signal "BOTTOM")
		(9 "F.Adhes" user "F.Adhesive")
		(11 "B.Adhes" user "B.Adhesive")
		(13 "F.Paste" user "Package Geometry/Pastemask Top")
		(15 "B.Paste" user "Package Geometry/Pastemask Bottom")
		(5 "F.SilkS" user "Ref Des/Silkscreen Top")
		(7 "B.SilkS" user "Ref Des/Silkscreen Bottom")
		(1 "F.Mask" user "Board Geometry/Soldermask Top")
		(3 "B.Mask" user "Board Geometry/Soldermask Bottom")
		(17 "Dwgs.User" user "User.Drawings")
		(19 "Cmts.User" user "User.Comments")
		(21 "Eco1.User" user "User.Eco1")
		(23 "Eco2.User" user "User.Eco2")
		(25 "Edge.Cuts" user "Board Geometry/Outline")
		(27 "Margin" user)
		(31 "F.CrtYd" user "Package Geometry/Place Bound Top")
		(29 "B.CrtYd" user "Package Geometry/Place Bound Bottom")
		(35 "F.Fab" user "Ref Des/Assembly Top")
		(33 "B.Fab" user "Ref Des/Assembly Bottom")
	)
	(footprint ""
		(layer "F.Cu")
		(at 271.092676 -117.48135)
		(property "Reference" "R6229"
			(at 0 0 0)
			(layer "F.SilkS")
			(hide yes)
			(effects
				(font
					(size 1.27 1.27)
				)
			)
		)
		(property "Value" ""
			(at 0 0 0)
			(layer "F.Fab")
			(effects
				(font
					(size 1.27 1.27)
				)
			)
		)
		(duplicate_pad_numbers_are_jumpers no)
		(fp_line
			(start -0.7874 -0.4064)
			(end 0.7874 -0.4064)
			(stroke
				(width 0.1524)
				(type default)
			)
			(layer "F.SilkS")
		)
		(fp_line
			(start -0.7874 0.4064)
			(end -0.7874 -0.4064)
			(stroke
				(width 0.1524)
				(type default)
			)
			(layer "F.SilkS")
		)
		(fp_line
			(start 0.7874 -0.4064)
			(end 0.7874 0.4064)
			(stroke
				(width 0.1524)
				(type default)
			)
			(layer "F.SilkS")
		)
		(fp_line
			(start 0.7874 0.4064)
			(end -0.7874 0.4064)
			(stroke
				(width 0.1524)
				(type default)
			)
			(layer "F.SilkS")
		)
		(fp_line
			(start -0.67945 -0.305054)
			(end -0.12065 -0.305054)
			(stroke
				(width 0.1)
				(type default)
			)
			(layer "F.Fab")
		)
		(fp_line
			(start -0.67945 0.3048)
			(end -0.67945 -0.305054)
			(stroke
				(width 0.1)
				(type default)
			)
			(layer "F.Fab")
		)
		(fp_line
			(start -0.12065 -0.305054)
			(end -0.12065 -0.2794)
			(stroke
				(width 0.1)
				(type default)
			)
			(layer "F.Fab")
		)
		(fp_line
			(start -0.12065 -0.2794)
			(end 0.12065 -0.2794)
			(stroke
				(width 0.1)
				(type default)
			)
			(layer "F.Fab")
		)
		(fp_line
			(start -0.12065 0.2794)
			(end -0.12065 0.3048)
			(stroke
				(width 0.1)
				(type default)
			)
			(layer "F.Fab")
		)
		(fp_line
			(start -0.12065 0.3048)
			(end -0.67945 0.3048)
			(stroke
				(width 0.1)
				(type default)
			)
			(layer "F.Fab")
		)
		(fp_line
			(start 0.120396 0.2794)
			(end -0.12065 0.2794)
			(stroke
				(width 0.1)
				(type default)
			)
			(layer "F.Fab")
		)
		(fp_line
			(start 0.120396 0.3048)
			(end 0.120396 0.2794)
			(stroke
				(width 0.1)
				(type default)
			)
			(layer "F.Fab")
		)
		(fp_line
			(start 0.12065 -0.3048)
			(end 0.67945 -0.3048)
			(stroke
				(width 0.1)
				(type default)
			)
			(layer "F.Fab")
		)
		(fp_line
			(start 0.12065 -0.2794)
			(end 0.12065 -0.3048)
			(stroke
				(width 0.1)
				(type default)
			)
			(layer "F.Fab")
		)
		(fp_line
			(start 0.67945 -0.3048)
			(end 0.67945 0.3048)
			(stroke
				(width 0.1)
				(type default)
			)
			(layer "F.Fab")
		)
		(fp_line
			(start 0.67945 0.3048)
			(end 0.120396 0.3048)
			(stroke
				(width 0.1)
				(type default)
			)
			(layer "F.Fab")
		)
		(pad "1" smd circle
			(at -0.40005 0)
			(size 0 0)
			(layers "F.Cu" "F.Mask" "F.Paste")
			(net "SMB_P12V_HSC_SCL_R")
		)
		(pad "2" smd circle
			(at 0.40005 0)
			(size 0 0)
			(layers "F.Cu" "F.Mask" "F.Paste")
			(net "SMB_P12V_HSC_SCL")
		)
	)
	(footprint ""
		(layer "F.Cu")
		(at 361.22229 -393.9032 90)
		(property "Reference" "R1015"
			(at 0 0 90)
			(layer "F.SilkS")
			(hide yes)
			(effects
				(font
					(size 1.27 1.27)
				)
			)
		)
		(property "Value" ""
			(at 0 0 90)
			(layer "F.Fab")
			(effects
				(font
					(size 1.27 1.27)
				)
			)
		)
		(duplicate_pad_numbers_are_jumpers no)
		(fp_line
			(start 0.32512 -0.175006)
			(end 0.32512 0.175006)
			(stroke
				(width 0.1)
				(type default)
			)
			(layer "F.Fab")
		)
		(fp_line
			(start -0.32512 -0.175006)
			(end 0.32512 -0.175006)
			(stroke
				(width 0.1)
				(type default)
			)
			(layer "F.Fab")
		)
		(fp_line
			(start 0.32512 0.175006)
			(end -0.32512 0.175006)
			(stroke
				(width 0.1)
				(type default)
			)
			(layer "F.Fab")
		)
		(fp_line
			(start -0.32512 0.175006)
			(end -0.32512 -0.175006)
			(stroke
				(width 0.1)
				(type default)
			)
			(layer "F.Fab")
		)
		(pad "1" smd rect
			(at -0.2667 0 90)
			(size 0.3048 0.381)
			(layers "F.Cu" "F.Mask" "F.Paste")
			(net "P1V8_CPU0_RT_1D")
		)
		(pad "2" smd rect
			(at 0.2667 0 270)
			(size 0.3048 0.381)
			(layers "F.Cu" "F.Mask" "F.Paste")
			(net "RT_CPU0_P1_ADDR2")
		)
	)
	(footprint ""
		(layer "F.Cu")
		(at 141.197838 -168.30167)
		(property "Reference" "TP20"
			(at 1.07442 0.112268 0)
			(unlocked yes)
			(layer "F.SilkS")
			(effects
				(font
					(size 0.7874 0.5842)
					(thickness 0.1524)
				)
				(justify left)
			)
		)
		(property "Value" ""
			(at 0 0 0)
			(layer "F.Fab")
			(effects
				(font
					(size 1.27 1.27)
				)
			)
		)
		(duplicate_pad_numbers_are_jumpers no)
		(pad "1" smd circle
			(at 0 0)
			(size 0.762 0.762)
			(layers "F.Cu" "F.Mask" "F.Paste")
			(net "VSENSE_PVDDCR_SOC_P1_DP")
		)
	)
	(footprint ""
		(layer "F.Cu")
		(at 163.144454 -38.493954 -90)
		(property "Reference" "R2487"
			(at 0 0 270)
			(layer "F.SilkS")
			(hide yes)
			(effects
				(font
					(size 1.27 1.27)
				)
			)
		)
		(property "Value" ""
			(at 0 0 270)
			(layer "F.Fab")
			(effects
				(font
					(size 1.27 1.27)
				)
			)
		)
		(duplicate_pad_numbers_are_jumpers no)
		(fp_line
			(start -0.7874 0.4064)
			(end -0.7874 -0.4064)
			(stroke
				(width 0.1524)
				(type default)
			)
			(layer "F.SilkS")
		)
		(fp_line
			(start 0.7874 0.4064)
			(end -0.7874 0.4064)
			(stroke
				(width 0.1524)
				(type default)
			)
			(layer "F.SilkS")
		)
		(fp_line
			(start -0.7874 -0.4064)
			(end 0.7874 -0.4064)
			(stroke
				(width 0.1524)
				(type default)
			)
			(layer "F.SilkS")
		)
		(fp_line
			(start 0.7874 -0.4064)
			(end 0.7874 0.4064)
			(stroke
				(width 0.1524)
				(type default)
			)
			(layer "F.SilkS")
		)
		(fp_line
			(start -0.67945 0.3048)
			(end -0.67945 -0.305054)
			(stroke
				(width 0.1)
				(type default)
			)
			(layer "F.Fab")
		)
		(fp_line
			(start -0.12065 0.3048)
			(end -0.67945 0.3048)
			(stroke
				(width 0.1)
				(type default)
			)
			(layer "F.Fab")
		)
		(fp_line
			(start 0.120396 0.3048)
			(end 0.120396 0.2794)
			(stroke
				(width 0.1)
				(type default)
			)
			(layer "F.Fab")
		)
		(fp_line
			(start 0.67945 0.3048)
			(end 0.120396 0.3048)
			(stroke
				(width 0.1)
				(type default)
			)
			(layer "F.Fab")
		)
		(fp_line
			(start -0.12065 0.2794)
			(end -0.12065 0.3048)
			(stroke
				(width 0.1)
				(type default)
			)
			(layer "F.Fab")
		)
		(fp_line
			(start 0.120396 0.2794)
			(end -0.12065 0.2794)
			(stroke
				(width 0.1)
				(type default)
			)
			(layer "F.Fab")
		)
		(fp_line
			(start -0.12065 -0.2794)
			(end 0.12065 -0.2794)
			(stroke
				(width 0.1)
				(type default)
			)
			(layer "F.Fab")
		)
		(fp_line
			(start 0.12065 -0.2794)
			(end 0.12065 -0.3048)
			(stroke
				(width 0.1)
				(type default)
			)
			(layer "F.Fab")
		)
		(fp_line
			(start 0.12065 -0.3048)
			(end 0.67945 -0.3048)
			(stroke
				(width 0.1)
				(type default)
			)
			(layer "F.Fab")
		)
		(fp_line
			(start 0.67945 -0.3048)
			(end 0.67945 0.3048)
			(stroke
				(width 0.1)
				(type default)
			)
			(layer "F.Fab")
		)
		(fp_line
			(start -0.67945 -0.305054)
			(end -0.12065 -0.305054)
			(stroke
				(width 0.1)
				(type default)
			)
			(layer "F.Fab")
		)
		(fp_line
			(start -0.12065 -0.305054)
			(end -0.12065 -0.2794)
			(stroke
				(width 0.1)
				(type default)
			)
			(layer "F.Fab")
		)
		(pad "1" smd circle
			(at -0.40005 0 270)
			(size 0 0)
			(layers "F.Cu" "F.Mask" "F.Paste")
			(net "P3V3_AUX")
		)
		(pad "2" smd circle
			(at 0.40005 0 270)
			(size 0 0)
			(layers "F.Cu" "F.Mask" "F.Paste")
			(net "IRQ_LVC3_WAKE_BUF_N")
		)
	)
)
